(kicad_pcb
	(version 20260206)
	(generator "pcbnew")
	(generator_version "10.0")
	(general
		(thickness 1.6)
		(legacy_teardrops no)
	)
	(paper "A4")
	(title_block
		(title "Bryce Canyon_R.DPB_16317-1_OCP.brd")
		(comment 1 "Bryce Canyon / footprints 2013-2017 of 2099")
	)
	(layers
		(0 "F.Cu" signal "TOP")
		(4 "In1.Cu" signal "L2GND")
		(6 "In2.Cu" signal "L3")
		(8 "In3.Cu" signal "L4VCC")
		(10 "In4.Cu" signal "L5VCC")
		(12 "In5.Cu" signal "L6")
		(14 "In6.Cu" signal "L7GND")
		(2 "B.Cu" signal "BOTTOM")
		(9 "F.Adhes" user "F.Adhesive")
		(11 "B.Adhes" user "B.Adhesive")
		(13 "F.Paste" user "Package Geometry/Pastemask Top")
		(15 "B.Paste" user "Package Geometry/Pastemask Bottom")
		(5 "F.SilkS" user "Ref Des/Silkscreen Top")
		(7 "B.SilkS" user "Ref Des/Silkscreen Bottom")
		(1 "F.Mask" user "Board Geometry/Soldermask Top")
		(3 "B.Mask" user "Board Geometry/Soldermask Bottom")
		(17 "Dwgs.User" user "User.Drawings")
		(19 "Cmts.User" user "User.Comments")
		(21 "Eco1.User" user "User.Eco1")
		(23 "Eco2.User" user "User.Eco2")
		(25 "Edge.Cuts" user "Board Geometry/Outline")
		(27 "Margin" user)
		(31 "F.CrtYd" user "Package Geometry/Place Bound Top")
		(29 "B.CrtYd" user "Package Geometry/Place Bound Bottom")
		(35 "F.Fab" user "Ref Des/Assembly Top")
		(33 "B.Fab" user "Ref Des/Assembly Bottom")
	)
	(footprint ""
		(layer "B.Cu")
		(at 448.664584 -111.780828 90)
		(property "Reference" "L8"
			(at 0 0 90)
			(layer "B.SilkS")
			(hide yes)
			(effects
				(font
					(size 1.27 1.27)
				)
				(justify mirror)
			)
		)
		(property "Value" "IND-1UH-191-GP"
			(at 6.7818 -2.1082 90)
			(unlocked yes)
			(layer "B.Fab")
			(hide yes)
			(effects
				(font
					(size 1.016 1.016)
					(thickness 0.1524)
				)
				(justify mirror)
			)
		)
		(property "Device Type" "L109100-2430-UH119"
			(at 6.7818 -3.6322 90)
			(unlocked yes)
			(layer "B.Fab")
			(hide yes)
			(effects
				(font
					(size 1.016 1.016)
					(thickness 0.1524)
				)
				(justify mirror)
			)
		)
		(duplicate_pad_numbers_are_jumpers no)
		(fp_line
			(start 5.2578 -6.4262)
			(end -5.2578 -6.4262)
			(stroke
				(width 0.1524)
				(type default)
			)
			(layer "B.SilkS")
		)
		(fp_line
			(start -5.2578 -6.4262)
			(end -5.2578 6.4262)
			(stroke
				(width 0.1524)
				(type default)
			)
			(layer "B.SilkS")
		)
		(fp_line
			(start 5.2578 6.4262)
			(end 5.2578 -6.4262)
			(stroke
				(width 0.1524)
				(type default)
			)
			(layer "B.SilkS")
		)
		(fp_line
			(start -5.2578 6.4262)
			(end 5.2578 6.4262)
			(stroke
				(width 0.1524)
				(type default)
			)
			(layer "B.SilkS")
		)
		(fp_rect
			(start 5.0038 5.4229)
			(end -5.0038 -5.4229)
			(stroke
				(width 0)
				(type default)
			)
			(fill no)
			(layer "B.CrtYd")
		)
		(fp_poly
			(pts
				(xy 5.5118 6.5024) (xy 5.5118 -6.5024) (xy -5.5118 -6.5024) (xy -5.5118 -0.8509) (xy -5.0038 -0.8509)
				(xy -5.0038 -5.4229) (xy 5.0038 -5.4229) (xy 5.0038 5.4229) (xy -5.0038 5.4229) (xy -5.0038 -0.8382)
				(xy -5.5118 -0.8382) (xy -5.5118 6.5024)
			)
			(stroke
				(width 0)
				(type default)
			)
			(fill no)
			(layer "B.CrtYd")
		)
		(fp_rect
			(start 5.5118 6.5024)
			(end -5.5118 -6.5024)
			(stroke
				(width 0)
				(type default)
			)
			(fill no)
			(layer "B.Fab")
		)
		(pad "1" smd rect
			(at 0 -4.396994 270)
			(size 3.5052 3.556)
			(layers "B.Cu" "B.Mask" "B.Paste")
			(net "P5V_B_4_LL")
		)
		(pad "2" smd rect
			(at 0 4.396994 270)
			(size 3.5052 3.556)
			(layers "B.Cu" "B.Mask" "B.Paste")
			(net "P5V_B_4")
		)
	)
	(footprint ""
		(layer "B.Cu")
		(at 130.694684 -366.349788 90)
		(property "Reference" "C378"
			(at 0 0 90)
			(layer "B.SilkS")
			(hide yes)
			(effects
				(font
					(size 1.27 1.27)
				)
				(justify mirror)
			)
		)
		(property "Value" "SCD033U25V2KX-GP"
			(at -1.1811 -2.7051 90)
			(unlocked yes)
			(layer "B.Fab")
			(hide yes)
			(effects
				(font
					(size 1.016 1.016)
					(thickness 0.1524)
				)
				(justify mirror)
			)
		)
		(property "Device Type" "C402H22"
			(at -1.1811 -4.2291 90)
			(unlocked yes)
			(layer "B.Fab")
			(hide yes)
			(effects
				(font
					(size 1.016 1.016)
					(thickness 0.1524)
				)
				(justify mirror)
			)
		)
		(duplicate_pad_numbers_are_jumpers no)
		(fp_rect
			(start 0.4318 0.9525)
			(end -0.4318 -0.9525)
			(stroke
				(width 0)
				(type default)
			)
			(fill no)
			(layer "B.CrtYd")
		)
		(fp_rect
			(start 0.4318 0.9525)
			(end -0.4318 -0.9525)
			(stroke
				(width 0)
				(type default)
			)
			(fill no)
			(layer "B.Fab")
		)
		(pad "1" smd custom
			(at 0 -0.4445 270)
			(size 0.1524 0.1524)
			(layers "B.Cu" "B.Mask" "B.Paste")
			(net "GATE_FAN1_R")
			(options
				(clearance outline)
				(anchor circle)
			)
			(primitives
				(gr_poly
					(pts
						(arc
							(start 0.3048 0.2032)
							(mid 0.275042 0.275042)
							(end 0.2032 0.3048)
						)
						(arc
							(start -0.2032 0.3048)
							(mid -0.275042 0.275042)
							(end -0.3048 0.2032)
						)
						(arc
							(start -0.3048 -0.2032)
							(mid -0.275042 -0.275042)
							(end -0.2032 -0.3048)
						)
						(arc
							(start 0.2032 -0.3048)
							(mid 0.275042 -0.275042)
							(end 0.3048 -0.2032)
						)
					)
					(width 0)
					(fill yes)
				)
			)
		)
		(pad "2" smd custom
			(at 0 0.4445 270)
			(size 0.1524 0.1524)
			(layers "B.Cu" "B.Mask" "B.Paste")
			(net "P12V_IN")
			(options
				(clearance outline)
				(anchor circle)
			)
			(primitives
				(gr_poly
					(pts
						(arc
							(start 0.3048 0.2032)
							(mid 0.275042 0.275042)
							(end 0.2032 0.3048)
						)
						(arc
							(start -0.2032 0.3048)
							(mid -0.275042 0.275042)
							(end -0.3048 0.2032)
						)
						(arc
							(start -0.3048 -0.2032)
							(mid -0.275042 -0.275042)
							(end -0.2032 -0.3048)
						)
						(arc
							(start 0.2032 -0.3048)
							(mid 0.275042 -0.275042)
							(end 0.3048 -0.2032)
						)
					)
					(width 0)
					(fill yes)
				)
			)
		)
	)
	(footprint ""
		(layer "B.Cu")
		(at 247.292114 -279.831546 -90)
		(property "Reference" "L9"
			(at 0 0 90)
			(layer "B.SilkS")
			(hide yes)
			(effects
				(font
					(size 1.27 1.27)
				)
				(justify mirror)
			)
		)
		(property "Value" "COIL-4D7UH-33-GP"
			(at 4.699 -4.0132 270)
			(unlocked yes)
			(layer "B.Fab")
			(hide yes)
			(effects
				(font
					(size 1.016 1.016)
					(thickness 0.1524)
				)
				(justify mirror)
			)
		)
		(property "Device Type" "L7066-1830-UH119"
			(at 4.699 -5.5372 270)
			(unlocked yes)
			(layer "B.Fab")
			(hide yes)
			(effects
				(font
					(size 1.016 1.016)
					(thickness 0.1524)
				)
				(justify mirror)
			)
		)
		(duplicate_pad_numbers_are_jumpers no)
		(fp_line
			(start -3.556 4.4958)
			(end 3.556 4.4958)
			(stroke
				(width 0.1524)
				(type default)
			)
			(layer "B.SilkS")
		)
		(fp_line
			(start 3.556 4.4958)
			(end 3.556 -4.4958)
			(stroke
				(width 0.1524)
				(type default)
			)
			(layer "B.SilkS")
		)
		(fp_line
			(start -3.556 -4.4958)
			(end -3.556 4.4958)
			(stroke
				(width 0.1524)
				(type default)
			)
			(layer "B.SilkS")
		)
		(fp_line
			(start 3.556 -4.4958)
			(end -3.556 -4.4958)
			(stroke
				(width 0.1524)
				(type default)
			)
			(layer "B.SilkS")
		)
		(fp_rect
			(start 3.302 3.4798)
			(end -3.302 -3.4798)
			(stroke
				(width 0)
				(type default)
			)
			(fill no)
			(layer "B.CrtYd")
		)
		(fp_poly
			(pts
				(xy 3.81 4.572) (xy 3.81 -4.572) (xy -3.81 -4.572) (xy -3.81 -0.5588) (xy -3.302 -0.5588) (xy -3.302 -3.4798)
				(xy 3.302 -3.4798) (xy 3.302 3.4798) (xy -3.302 3.4798) (xy -3.302 -0.5461) (xy -3.81 -0.5461) (xy -3.81 4.572)
			)
			(stroke
				(width 0)
				(type default)
			)
			(fill no)
			(layer "B.CrtYd")
		)
		(fp_rect
			(start 3.81 4.572)
			(end -3.81 -4.572)
			(stroke
				(width 0)
				(type default)
			)
			(fill no)
			(layer "B.Fab")
		)
		(pad "1" smd rect
			(at 0 -2.779522 90)
			(size 3.5052 2.921)
			(layers "B.Cu" "B.Mask" "B.Paste")
			(net "P3V3_STBY_SW")
		)
		(pad "2" smd rect
			(at 0 2.779522 90)
			(size 3.5052 2.921)
			(layers "B.Cu" "B.Mask" "B.Paste")
			(net "P3V3_STBY_B")
		)
	)
	(footprint ""
		(layer "B.Cu")
		(at 254.428498 -282.320746 -90)
		(property "Reference" "U35"
			(at 0 0 90)
			(layer "B.SilkS")
			(hide yes)
			(effects
				(font
					(size 1.27 1.27)
				)
				(justify mirror)
			)
		)
		(property "Value" "TPS53312RGTR-GP"
			(at -4.9784 -6.9342 270)
			(unlocked yes)
			(layer "B.Fab")
			(hide yes)
			(effects
				(font
					(size 1.016 1.016)
					(thickness 0.1524)
				)
				(justify mirror)
			)
		)
		(property "Device Type" "QFN16G3-G1D7H40"
			(at -4.9784 -8.4582 270)
			(unlocked yes)
			(layer "B.Fab")
			(hide yes)
			(effects
				(font
					(size 1.016 1.016)
					(thickness 0.1524)
				)
				(justify mirror)
			)
		)
		(duplicate_pad_numbers_are_jumpers no)
		(fp_line
			(start -2.5146 2.5146)
			(end -2.5146 1.2446)
			(stroke
				(width 0.1524)
				(type default)
			)
			(layer "B.SilkS")
		)
		(fp_line
			(start -1.2446 2.5146)
			(end -2.5146 2.5146)
			(stroke
				(width 0.1524)
				(type default)
			)
			(layer "B.SilkS")
		)
		(fp_line
			(start 2.5146 2.5146)
			(end 1.2446 2.5146)
			(stroke
				(width 0.1524)
				(type default)
			)
			(layer "B.SilkS")
		)
		(fp_line
			(start 0.249936 2.262124)
			(end 0.249936 3.024124)
			(stroke
				(width 0.1524)
				(type default)
			)
			(layer "B.SilkS")
		)
		(fp_line
			(start 2.5146 1.2446)
			(end 2.5146 2.5146)
			(stroke
				(width 0.1524)
				(type default)
			)
			(layer "B.SilkS")
		)
		(fp_line
			(start -2.262124 -0.249936)
			(end -2.770124 -0.249936)
			(stroke
				(width 0.1524)
				(type default)
			)
			(layer "B.SilkS")
		)
		(fp_line
			(start 2.262124 -0.750062)
			(end 2.770124 -0.750062)
			(stroke
				(width 0.1524)
				(type default)
			)
			(layer "B.SilkS")
		)
		(fp_line
			(start 1.2446 -2.5146)
			(end 2.5146 -2.5146)
			(stroke
				(width 0.1524)
				(type default)
			)
			(layer "B.SilkS")
		)
		(fp_line
			(start 2.5146 -2.5146)
			(end 2.5146 -1.2446)
			(stroke
				(width 0.1524)
				(type default)
			)
			(layer "B.SilkS")
		)
		(fp_poly
			(pts
				(xy -2.5146 -2.5146) (xy -1.2446 -2.5146) (xy -2.5146 -1.2446)
			)
			(stroke
				(width 0)
				(type default)
			)
			(fill yes)
			(layer "B.SilkS")
		)
		(fp_rect
			(start 1.4986 1.4986)
			(end -1.4986 -1.4986)
			(stroke
				(width 0)
				(type default)
			)
			(fill no)
			(layer "B.CrtYd")
		)
		(fp_poly
			(pts
				(xy -2.5146 -1.4986) (xy 1.4986 -1.4986) (xy 1.4986 1.4986) (xy -1.4986 1.4986) (xy -1.4986 -1.4859)
				(xy -2.5146 -1.4859) (xy -2.5146 2.5146) (xy 2.5146 2.5146) (xy 2.5146 -2.5146) (xy -2.5146 -2.5146)
			)
			(stroke
				(width 0)
				(type default)
			)
			(fill no)
			(layer "B.CrtYd")
		)
		(fp_rect
			(start 2.5146 2.5146)
			(end -2.5146 -2.5146)
			(stroke
				(width 0)
				(type default)
			)
			(fill no)
			(layer "B.Fab")
		)
		(pad "1" smd rect
			(at -0.750062 -1.550924 90)
			(size 0.3048 0.9144)
			(layers "B.Cu" "B.Mask" "B.Paste")
			(net "P3V3_STBY_VFB")
		)
		(pad "2" smd rect
			(at -0.249936 -1.538224 90)
			(size 0.3048 0.9398)
			(layers "B.Cu" "B.Mask" "B.Paste")
			(net "P3V3_STBY_VRG5")
		)
		(pad "3" smd rect
			(at 0.249936 -1.538224 90)
			(size 0.3048 0.9398)
			(layers "B.Cu" "B.Mask" "B.Paste")
			(net "P3V3_STBY_SS")
		)
		(pad "4" smd rect
			(at 0.750062 -1.550924 90)
			(size 0.3048 0.9144)
			(layers "B.Cu" "B.Mask" "B.Paste")
			(net "AGND_P3V3_STBY")
		)
		(pad "5" smd rect
			(at 1.550924 -0.750062 90)
			(size 0.9144 0.3048)
			(layers "B.Cu" "B.Mask" "B.Paste")
			(net "PWRGD_P3V3_STBY")
		)
		(pad "6" smd rect
			(at 1.538224 -0.249936 90)
			(size 0.9398 0.3048)
			(layers "B.Cu" "B.Mask" "B.Paste")
			(net "P3V3_STBY_EN_R")
		)
		(pad "7" smd rect
			(at 1.538224 0.249936 90)
			(size 0.9398 0.3048)
			(layers "B.Cu" "B.Mask" "B.Paste")
			(net "GND")
		)
		(pad "8" smd rect
			(at 1.550924 0.750062 90)
			(size 0.9144 0.3048)
			(layers "B.Cu" "B.Mask" "B.Paste")
			(net "GND")
		)
		(pad "9" smd rect
			(at 0.750062 1.550924 90)
			(size 0.3048 0.9144)
			(layers "B.Cu" "B.Mask" "B.Paste")
			(net "P3V3_STBY_SW")
		)
		(pad "10" smd rect
			(at 0.249936 1.538224 90)
			(size 0.3048 0.9398)
			(layers "B.Cu" "B.Mask" "B.Paste")
			(net "P3V3_STBY_SW")
		)
		(pad "11" smd rect
			(at -0.249936 1.538224 90)
			(size 0.3048 0.9398)
			(layers "B.Cu" "B.Mask" "B.Paste")
			(net "P3V3_STBY_SW")
		)
		(pad "12" smd rect
			(at -0.750062 1.550924 90)
			(size 0.3048 0.9144)
			(layers "B.Cu" "B.Mask" "B.Paste")
			(net "P3V3_STBY_VBST")
		)
		(pad "13" smd rect
			(at -1.550924 0.750062 90)
			(size 0.9144 0.3048)
			(layers "B.Cu" "B.Mask" "B.Paste")
			(net "P3V3_STBY_VIN")
		)
		(pad "14" smd rect
			(at -1.538224 0.249936 90)
			(size 0.9398 0.3048)
			(layers "B.Cu" "B.Mask" "B.Paste")
			(net "P3V3_STBY_VIN")
		)
		(pad "15" smd rect
			(at -1.538224 -0.249936 90)
			(size 0.9398 0.3048)
			(layers "B.Cu" "B.Mask" "B.Paste")
			(net "P3V3_STBY_VCC")
		)
		(pad "16" smd rect
			(at -1.550924 -0.750062 90)
			(size 0.9144 0.3048)
			(layers "B.Cu" "B.Mask" "B.Paste")
			(net "P3V3_STBY_VO")
		)
		(pad "17" smd rect
			(at 0 0 90)
			(size 1.6764 1.6764)
			(layers "B.Cu" "B.Mask" "B.Paste")
			(net "GND")
		)
	)
	(footprint ""
		(layer "B.Cu")
		(at 457.833984 -109.745018)
		(property "Reference" "TC7"
			(at 0 0 0)
			(layer "B.SilkS")
			(hide yes)
			(effects
				(font
					(size 1.27 1.27)
				)
				(justify mirror)
			)
		)
		(property "Value" "ST220U10VDM-LGP"
			(at 0 -9.6012 0)
			(unlocked yes)
			(layer "B.Fab")
			(hide yes)
			(effects
				(font
					(size 1.016 1.016)
					(thickness 0.1524)
				)
				(justify mirror)
			)
		)
		(property "Device Type" "CT7343H119"
			(at 0 -11.1252 0)
			(unlocked yes)
			(layer "B.Fab")
			(hide yes)
			(effects
				(font
					(size 1.016 1.016)
					(thickness 0.1524)
				)
				(justify mirror)
			)
		)
		(duplicate_pad_numbers_are_jumpers no)
		(fp_line
			(start -2.286 -4.8768)
			(end 2.286 -4.8768)
			(stroke
				(width 0.1524)
				(type default)
			)
			(layer "B.SilkS")
		)
		(fp_line
			(start -2.286 -2.032)
			(end -2.286 -4.8768)
			(stroke
				(width 0.1524)
				(type default)
			)
			(layer "B.SilkS")
		)
		(fp_line
			(start -2.286 2.032)
			(end -2.286 4.8768)
			(stroke
				(width 0.1524)
				(type default)
			)
			(layer "B.SilkS")
		)
		(fp_line
			(start -2.286 4.8768)
			(end 2.286 4.8768)
			(stroke
				(width 0.1524)
				(type default)
			)
			(layer "B.SilkS")
		)
		(fp_line
			(start -2.1082 -4.699)
			(end 2.1082 -4.699)
			(stroke
				(width 0.508)
				(type default)
			)
			(layer "B.SilkS")
		)
		(fp_line
			(start 2.286 -4.8768)
			(end 2.286 -2.032)
			(stroke
				(width 0.1524)
				(type default)
			)
			(layer "B.SilkS")
		)
		(fp_line
			(start 2.286 4.8768)
			(end 2.286 2.032)
			(stroke
				(width 0.1524)
				(type default)
			)
			(layer "B.SilkS")
		)
		(fp_rect
			(start 2.1463 3.6449)
			(end -2.1463 -3.6449)
			(stroke
				(width 0)
				(type default)
			)
			(fill no)
			(layer "B.CrtYd")
		)
		(fp_poly
			(pts
				(xy 2.54 4.953) (xy 2.54 4.2926) (xy 3.81 4.2926) (xy 3.81 -4.2926) (xy 2.54 -4.2926) (xy 2.54 -4.953)
				(xy -2.54 -4.953) (xy -2.54 -4.2926) (xy -3.81 -4.2926) (xy -3.81 -1.6256) (xy -2.1463 -1.6256)
				(xy -2.1463 -3.6449) (xy 2.1463 -3.6449) (xy 2.1463 3.6449) (xy -2.1463 3.6449) (xy -2.1463 -1.6129)
				(xy -3.81 -1.6129) (xy -3.81 4.2926) (xy -2.54 4.2926) (xy -2.54 4.953)
			)
			(stroke
				(width 0)
				(type default)
			)
			(fill no)
			(layer "B.CrtYd")
		)
		(fp_rect
			(start -2.54 4.2926)
			(end -3.81 -4.2926)
			(stroke
				(width 0)
				(type default)
			)
			(fill no)
			(layer "B.Fab")
		)
		(fp_rect
			(start 2.54 4.953)
			(end -2.54 -4.953)
			(stroke
				(width 0)
				(type default)
			)
			(fill no)
			(layer "B.Fab")
		)
		(fp_rect
			(start 3.81 4.2926)
			(end 2.54 -4.2926)
			(stroke
				(width 0)
				(type default)
			)
			(fill no)
			(layer "B.Fab")
		)
		(pad "1" smd rect
			(at 0 -3.1496 180)
			(size 2.413 2.286)
			(layers "B.Cu" "B.Mask" "B.Paste")
			(net "P5V_B_4")
		)
		(pad "2" smd rect
			(at 0 3.1496 180)
			(size 2.413 2.286)
			(layers "B.Cu" "B.Mask" "B.Paste")
			(net "GND")
		)
		(zone
			(layer "B.Cu")
			(hatch none 0.5)
			(connect_pads
				(clearance 0)
			)
			(min_thickness 0.25)
			(keepout
				(tracks allowed)
				(vias not_allowed)
				(pads allowed)
				(copperpour not_allowed)
				(footprints allowed)
			)
			(placement
				(enabled no)
				(sheetname "")
			)
			(fill
				(thermal_gap 0.5)
				(thermal_bridge_width 0.5)
				(island_removal_mode 0)
			)
			(polygon
				(pts
					(xy 456.322684 -111.434118) (xy 456.322684 -114.342418) (xy 459.345284 -114.342418) (xy 459.345284 -111.446818)
					(xy 459.345284 -111.116618) (xy 456.322684 -111.116618)
				)
			)
		)
		(zone
			(layer "B.Cu")
			(hatch none 0.5)
			(connect_pads
				(clearance 0)
			)
			(min_thickness 0.25)
			(keepout
				(tracks allowed)
				(vias not_allowed)
				(pads allowed)
				(copperpour not_allowed)
				(footprints allowed)
			)
			(placement
				(enabled no)
				(sheetname "")
			)
			(fill
				(thermal_gap 0.5)
				(thermal_bridge_width 0.5)
				(island_removal_mode 0)
			)
			(polygon
				(pts
					(xy 459.345284 -105.147618) (xy 456.322684 -105.147618) (xy 456.322684 -108.043218) (xy 456.322684 -108.373418)
					(xy 459.345284 -108.373418) (xy 459.345284 -108.043218)
				)
			)
		)
	)
)
